# BASEBOARD_FAB2 (Tioga Pass) — schematic netlist excerpt (pin names and nets, part order shuffled) for the footprints in the layout excerpt that follows; sources: Cadence DE-HDL packaged netlist, KiCad conversion of Wiwynn_Tioga_Pass_MB.brd

R5W1  RES  0.0 5% CHIP  pkg 0402  page 113 : A = P1V8_MCP_CPU0 ; B = JTAG_MCP_CPU0_TDI_R
R3N12  RES  4.75K 1% CHIP  pkg 0402  page 157 : A = P3V3_STBY ; B = FM_MP_PS_FAIL_N
C9N24  CAPP  470UF 2.5V 20% ALUM  pkg 3018  page 208 : A = PVCCIN_CPU1 ; B = GND

(kicad_pcb
	(version 20260206)
	(generator "pcbnew")
	(generator_version "10.0")
	(general
		(thickness 1.6)
		(legacy_teardrops no)
	)
	(paper "A4")
	(title_block
		(title "Wiwynn_Tioga_Pass_MB.brd")
		(comment 1 "Tioga Pass / footprints 3141-3143 of 4770")
	)
	(layers
		(0 "F.Cu" signal "TOP")
		(4 "In1.Cu" signal "L2GND")
		(6 "In2.Cu" signal "L3")
		(8 "In3.Cu" signal "L4GND")
		(10 "In4.Cu" signal "L5")
		(12 "In5.Cu" signal "L6GND")
		(14 "In6.Cu" signal "L7VCC")
		(16 "In7.Cu" signal "L8VCC")
		(18 "In8.Cu" signal "L9GND")
		(20 "In9.Cu" signal "L10")
		(22 "In10.Cu" signal "L11GND")
		(24 "In11.Cu" signal "L12")
		(26 "In12.Cu" signal "L13GND")
		(2 "B.Cu" signal "BOTTOM")
		(9 "F.Adhes" user "F.Adhesive")
		(11 "B.Adhes" user "B.Adhesive")
		(13 "F.Paste" user "Package Geometry/Pastemask Top")
		(15 "B.Paste" user "Package Geometry/Pastemask Bottom")
		(5 "F.SilkS" user "Ref Des/Silkscreen Top")
		(7 "B.SilkS" user "Ref Des/Silkscreen Bottom")
		(1 "F.Mask" user "Board Geometry/Soldermask Top")
		(3 "B.Mask" user "Board Geometry/Soldermask Bottom")
		(17 "Dwgs.User" user "User.Drawings")
		(19 "Cmts.User" user "User.Comments")
		(21 "Eco1.User" user "User.Eco1")
		(23 "Eco2.User" user "User.Eco2")
		(25 "Edge.Cuts" user "Board Geometry/Outline")
		(27 "Margin" user)
		(31 "F.CrtYd" user "Package Geometry/Place Bound Top")
		(29 "B.CrtYd" user "Package Geometry/Place Bound Bottom")
		(35 "F.Fab" user "Ref Des/Assembly Top")
		(33 "B.Fab" user "Ref Des/Assembly Bottom")
	)
	(footprint ""
		(layer "B.Cu")
		(at 386.842 -87.3125 180)
		(property "Reference" "R3N12"
			(at 0 0 0)
			(layer "B.SilkS")
			(hide yes)
			(effects
				(font
					(size 1.27 1.27)
				)
				(justify mirror)
			)
		)
		(property "Value" ""
			(at 0 0 0)
			(layer "B.Fab")
			(effects
				(font
					(size 1.27 1.27)
				)
				(justify mirror)
			)
		)
		(duplicate_pad_numbers_are_jumpers no)
		(fp_poly
			(pts
				(xy 0.2794 -0.1016) (xy -0.2794 -0.1016) (xy -0.2794 0.9906) (xy 0.2794 0.9906)
			)
			(stroke
				(width 0)
				(type default)
			)
			(fill no)
			(layer "B.CrtYd")
		)
		(fp_line
			(start 0.2794 0.9906)
			(end -0.2794 0.9906)
			(stroke
				(width 0.1)
				(type default)
			)
			(layer "B.Fab")
		)
		(fp_line
			(start 0.2794 -0.1016)
			(end 0.2794 0.9906)
			(stroke
				(width 0.1)
				(type default)
			)
			(layer "B.Fab")
		)
		(fp_line
			(start -0.2794 0.9906)
			(end -0.2794 -0.1016)
			(stroke
				(width 0.1)
				(type default)
			)
			(layer "B.Fab")
		)
		(fp_line
			(start -0.2794 -0.1016)
			(end 0.2794 -0.1016)
			(stroke
				(width 0.1)
				(type default)
			)
			(layer "B.Fab")
		)
		(pad "1" smd rect
			(at 0 0)
			(size 0.508 0.508)
			(layers "B.Cu" "B.Mask" "B.Paste")
			(net "P3V3_STBY")
		)
		(pad "2" smd rect
			(at 0 0.889)
			(size 0.508 0.508)
			(layers "B.Cu" "B.Mask" "B.Paste")
			(net "FM_MP_PS_FAIL_N")
		)
		(zone
			(layer "B.Cu")
			(hatch none 0.5)
			(connect_pads
				(clearance 0)
			)
			(min_thickness 0.25)
			(keepout
				(tracks not_allowed)
				(vias allowed)
				(pads allowed)
				(copperpour not_allowed)
				(footprints allowed)
			)
			(placement
				(enabled no)
				(sheetname "")
			)
			(fill
				(thermal_gap 0.5)
				(thermal_bridge_width 0.5)
				(island_removal_mode 0)
			)
			(polygon
				(pts
					(xy 386.588 -87.9475) (xy 387.096 -87.9475) (xy 387.096 -87.5665) (xy 386.588 -87.5665)
				)
			)
		)
		(zone
			(layer "B.Cu")
			(hatch none 0.5)
			(connect_pads
				(clearance 0)
			)
			(min_thickness 0.25)
			(keepout
				(tracks allowed)
				(vias not_allowed)
				(pads allowed)
				(copperpour not_allowed)
				(footprints allowed)
			)
			(placement
				(enabled no)
				(sheetname "")
			)
			(fill
				(thermal_gap 0.5)
				(thermal_bridge_width 0.5)
				(island_removal_mode 0)
			)
			(polygon
				(pts
					(xy 386.588 -87.5665) (xy 387.096 -87.5665) (xy 387.096 -87.9475) (xy 386.588 -87.9475)
				)
			)
		)
	)
	(footprint ""
		(layer "B.Cu")
		(at 45.212 -89.408 -90)
		(property "Reference" "C9N24"
			(at -0.35433 -3.937 0)
			(unlocked yes)
			(layer "B.SilkS")
			(effects
				(font
					(size 0.7874 0.5842)
					(thickness 0.1524)
				)
				(justify mirror)
			)
		)
		(property "Value" ""
			(at 0 0 90)
			(layer "B.Fab")
			(effects
				(font
					(size 1.27 1.27)
				)
				(justify mirror)
			)
		)
		(duplicate_pad_numbers_are_jumpers no)
		(fp_line
			(start -2.286 7.366)
			(end -1.600708 7.366)
			(stroke
				(width 0.1524)
				(type default)
			)
			(layer "B.SilkS")
		)
		(fp_line
			(start -2.286 7.366)
			(end -2.286 1.63195)
			(stroke
				(width 0.1524)
				(type default)
			)
			(layer "B.SilkS")
		)
		(fp_line
			(start 2.286 7.366)
			(end 1.60147 7.366)
			(stroke
				(width 0.1524)
				(type default)
			)
			(layer "B.SilkS")
		)
		(fp_line
			(start 2.286 7.366)
			(end 2.286 1.632712)
			(stroke
				(width 0.1524)
				(type default)
			)
			(layer "B.SilkS")
		)
		(fp_line
			(start -2.504948 1.633728)
			(end -1.6002 1.633728)
			(stroke
				(width 0.1524)
				(type default)
			)
			(layer "B.SilkS")
		)
		(fp_line
			(start 2.563114 1.633728)
			(end 1.6002 1.633728)
			(stroke
				(width 0.1524)
				(type default)
			)
			(layer "B.SilkS")
		)
		(fp_line
			(start -2.504948 -1.616456)
			(end -2.504948 1.633728)
			(stroke
				(width 0.1524)
				(type default)
			)
			(layer "B.SilkS")
		)
		(fp_line
			(start -1.6002 -1.616456)
			(end -2.504948 -1.616456)
			(stroke
				(width 0.1524)
				(type default)
			)
			(layer "B.SilkS")
		)
		(fp_line
			(start 1.6002 -1.616456)
			(end 2.563114 -1.616456)
			(stroke
				(width 0.1524)
				(type default)
			)
			(layer "B.SilkS")
		)
		(fp_line
			(start 2.563114 -1.616456)
			(end 2.563114 1.633728)
			(stroke
				(width 0.1524)
				(type default)
			)
			(layer "B.SilkS")
		)
		(fp_rect
			(start 2.286 7.366)
			(end -2.286 -0.254)
			(stroke
				(width 0)
				(type default)
			)
			(fill no)
			(layer "B.CrtYd")
		)
		(fp_line
			(start -2.286 7.366)
			(end 2.286 7.366)
			(stroke
				(width 0.1)
				(type default)
			)
			(layer "B.Fab")
		)
		(fp_line
			(start 2.286 7.366)
			(end 2.286 -0.254)
			(stroke
				(width 0.1)
				(type default)
			)
			(layer "B.Fab")
		)
		(fp_line
			(start -2.286 -0.254)
			(end -2.286 7.366)
			(stroke
				(width 0.1)
				(type default)
			)
			(layer "B.Fab")
		)
		(fp_line
			(start 2.286 -0.254)
			(end -2.286 -0.254)
			(stroke
				(width 0.1)
				(type default)
			)
			(layer "B.Fab")
		)
		(pad "1" smd rect
			(at 0 0 90)
			(size 2.54 3.048)
			(layers "B.Cu" "B.Mask" "B.Paste")
			(net "PVCCIN_CPU1")
		)
		(pad "2" smd rect
			(at 0 7.112 90)
			(size 2.54 3.048)
			(layers "B.Cu" "B.Mask" "B.Paste")
			(net "GND")
		)
	)
	(footprint ""
		(layer "B.Cu")
		(at 327.158096 -54.597808 90)
		(property "Reference" "R5W1"
			(at 0.8382 -0.67818 90)
			(unlocked yes)
			(layer "B.SilkS")
			(effects
				(font
					(size 0.4064 0.254)
					(thickness 0.1524)
				)
				(justify left mirror)
			)
		)
		(property "Value" ""
			(at 0 0 90)
			(layer "B.Fab")
			(effects
				(font
					(size 1.27 1.27)
				)
				(justify mirror)
			)
		)
		(duplicate_pad_numbers_are_jumpers no)
		(fp_poly
			(pts
				(xy 0.2794 -0.1016) (xy -0.2794 -0.1016) (xy -0.2794 0.9906) (xy 0.2794 0.9906)
			)
			(stroke
				(width 0)
				(type default)
			)
			(fill no)
			(layer "B.CrtYd")
		)
		(fp_line
			(start 0.2794 -0.1016)
			(end 0.2794 0.9906)
			(stroke
				(width 0.1)
				(type default)
			)
			(layer "B.Fab")
		)
		(fp_line
			(start -0.2794 -0.1016)
			(end 0.2794 -0.1016)
			(stroke
				(width 0.1)
				(type default)
			)
			(layer "B.Fab")
		)
		(fp_line
			(start 0.2794 0.9906)
			(end -0.2794 0.9906)
			(stroke
				(width 0.1)
				(type default)
			)
			(layer "B.Fab")
		)
		(fp_line
			(start -0.2794 0.9906)
			(end -0.2794 -0.1016)
			(stroke
				(width 0.1)
				(type default)
			)
			(layer "B.Fab")
		)
		(pad "1" smd rect
			(at 0 0 270)
			(size 0.508 0.508)
			(layers "B.Cu" "B.Mask" "B.Paste")
			(net "P1V8_MCP_CPU0")
		)
		(pad "2" smd rect
			(at 0 0.889 270)
			(size 0.508 0.508)
			(layers "B.Cu" "B.Mask" "B.Paste")
			(net "JTAG_MCP_CPU0_TDI_R")
		)
		(zone
			(layer "B.Cu")
			(hatch none 0.5)
			(connect_pads
				(clearance 0)
			)
			(min_thickness 0.25)
			(keepout
				(tracks allowed)
				(vias not_allowed)
				(pads allowed)
				(copperpour not_allowed)
				(footprints allowed)
			)
			(placement
				(enabled no)
				(sheetname "")
			)
			(fill
				(thermal_gap 0.5)
				(thermal_bridge_width 0.5)
				(island_removal_mode 0)
			)
			(polygon
				(pts
					(xy 327.412096 -54.851808) (xy 327.412096 -54.343808) (xy 327.793096 -54.343808) (xy 327.793096 -54.851808)
				)
			)
		)
		(zone
			(layer "B.Cu")
			(hatch none 0.5)
			(connect_pads
				(clearance 0)
			)
			(min_thickness 0.25)
			(keepout
				(tracks not_allowed)
				(vias allowed)
				(pads allowed)
				(copperpour not_allowed)
				(footprints allowed)
			)
			(placement
				(enabled no)
				(sheetname "")
			)
			(fill
				(thermal_gap 0.5)
				(thermal_bridge_width 0.5)
				(island_removal_mode 0)
			)
			(polygon
				(pts
					(xy 327.793096 -54.851808) (xy 327.793096 -54.343808) (xy 327.412096 -54.343808) (xy 327.412096 -54.851808)
				)
			)
		)
	)
)
